(kicad_pcb
	(version 20260206)
	(generator "pcbnew")
	(generator_version "10.0")
	(general
		(thickness 1.6)
		(legacy_teardrops no)
	)
	(paper "A4")
	(title_block
		(title "v1-chassis-manager — T6M_CM_d_v01_1031_1645.brd")
		(comment 1 "Open CloudServer (Microsoft) / footprints 839-841 of 2512")
	)
	(layers
		(0 "F.Cu" signal "TOP")
		(4 "In1.Cu" signal "GND1")
		(6 "In2.Cu" signal "IN1")
		(8 "In3.Cu" signal "VCC1")
		(10 "In4.Cu" signal "VCC2")
		(12 "In5.Cu" signal "GND2")
		(14 "In6.Cu" signal "IN2")
		(16 "In7.Cu" signal "IN3")
		(18 "In8.Cu" signal "GND3")
		(2 "B.Cu" signal "BOTTOM")
		(9 "F.Adhes" user "F.Adhesive")
		(11 "B.Adhes" user "B.Adhesive")
		(13 "F.Paste" user "Package Geometry/Pastemask Top")
		(15 "B.Paste" user "Package Geometry/Pastemask Bottom")
		(5 "F.SilkS" user "Ref Des/Silkscreen Top")
		(7 "B.SilkS" user "Ref Des/Silkscreen Bottom")
		(1 "F.Mask" user "Board Geometry/Soldermask Top")
		(3 "B.Mask" user "Board Geometry/Soldermask Bottom")
		(17 "Dwgs.User" user "User.Drawings")
		(19 "Cmts.User" user "User.Comments")
		(21 "Eco1.User" user "User.Eco1")
		(23 "Eco2.User" user "User.Eco2")
		(25 "Edge.Cuts" user "Board Geometry/Outline")
		(27 "Margin" user)
		(31 "F.CrtYd" user "Package Geometry/Place Bound Top")
		(29 "B.CrtYd" user "Package Geometry/Place Bound Bottom")
		(35 "F.Fab" user "Ref Des/Assembly Top")
		(33 "B.Fab" user "Ref Des/Assembly Bottom")
	)
	(footprint ""
		(layer "F.Cu")
		(at 111.871252 -166.52113)
		(property "Reference" "R673"
			(at -1.917192 -12.506198 0)
			(unlocked yes)
			(layer "F.SilkS")
			(effects
				(font
					(size 0.7874 0.5842)
					(thickness 0.1524)
				)
				(justify left)
			)
		)
		(property "Value" ""
			(at 0 0 0)
			(layer "F.Fab")
			(effects
				(font
					(size 1.27 1.27)
				)
			)
		)
		(duplicate_pad_numbers_are_jumpers no)
		(fp_line
			(start -0.7874 -0.4064)
			(end 0.7874 -0.4064)
			(stroke
				(width 0.1524)
				(type default)
			)
			(layer "F.SilkS")
		)
		(fp_line
			(start -0.7874 0.4064)
			(end -0.7874 -0.4064)
			(stroke
				(width 0.1524)
				(type default)
			)
			(layer "F.SilkS")
		)
		(fp_line
			(start 0.7874 -0.4064)
			(end 0.7874 0.4064)
			(stroke
				(width 0.1524)
				(type default)
			)
			(layer "F.SilkS")
		)
		(fp_line
			(start 0.7874 0.4064)
			(end -0.7874 0.4064)
			(stroke
				(width 0.1524)
				(type default)
			)
			(layer "F.SilkS")
		)
		(fp_poly
			(pts
				(xy -0.508 0.2794) (xy -0.508 0.2286) (xy -0.635 0.2286) (xy -0.635 -0.254) (xy -0.5334 -0.254)
				(xy -0.5334 -0.2794) (xy 0.5334 -0.2794) (xy 0.5334 -0.254) (xy 0.635 -0.254) (xy 0.635 0.254) (xy 0.5334 0.254)
				(xy 0.5334 0.2794)
			)
			(stroke
				(width 0)
				(type default)
			)
			(fill no)
			(layer "F.CrtYd")
		)
		(pad "1" smd rect
			(at 0.40005 0)
			(size 0.4572 0.508)
			(layers "F.Cu" "F.Mask" "F.Paste")
			(net "UART3_RESET_N")
		)
		(pad "2" smd rect
			(at -0.40005 0)
			(size 0.4572 0.508)
			(layers "F.Cu" "F.Mask" "F.Paste")
			(net "P3V3_NODE1")
		)
	)
	(footprint ""
		(layer "F.Cu")
		(at 10.65022 -46.794166 180)
		(property "Reference" "J9"
			(at -2.037842 0.385826 90)
			(unlocked yes)
			(layer "F.SilkS")
			(effects
				(font
					(size 0.7874 0.5842)
					(thickness 0.1524)
				)
				(justify left)
			)
		)
		(property "Value" ""
			(at 0 0 180)
			(layer "F.Fab")
			(effects
				(font
					(size 1.27 1.27)
				)
			)
		)
		(duplicate_pad_numbers_are_jumpers no)
		(fp_line
			(start 9.299956 19.50593)
			(end 9.299956 -11.494008)
			(stroke
				(width 0.1524)
				(type default)
			)
			(layer "F.SilkS")
		)
		(fp_line
			(start 9.299956 -11.494008)
			(end -1.299972 -11.494008)
			(stroke
				(width 0.1524)
				(type default)
			)
			(layer "F.SilkS")
		)
		(fp_line
			(start 3.10007 19.50593)
			(end 3.10007 -11.494008)
			(stroke
				(width 0.1524)
				(type default)
			)
			(layer "F.SilkS")
		)
		(fp_line
			(start 2.70002 19.50593)
			(end 2.70002 -11.494008)
			(stroke
				(width 0.1524)
				(type default)
			)
			(layer "F.SilkS")
		)
		(fp_line
			(start -1.299972 19.50593)
			(end 9.299956 19.50593)
			(stroke
				(width 0.1524)
				(type default)
			)
			(layer "F.SilkS")
		)
		(fp_line
			(start -1.299972 17.85112)
			(end -1.299972 19.50593)
			(stroke
				(width 0.1524)
				(type default)
			)
			(layer "F.SilkS")
		)
		(fp_line
			(start -1.299972 15.1511)
			(end -2.899918 15.1511)
			(stroke
				(width 0.1524)
				(type default)
			)
			(layer "F.SilkS")
		)
		(fp_line
			(start -1.299972 12.726416)
			(end -1.299972 15.1511)
			(stroke
				(width 0.1524)
				(type default)
			)
			(layer "F.SilkS")
		)
		(fp_line
			(start -1.299972 -3.24739)
			(end -1.299972 11.262106)
			(stroke
				(width 0.1524)
				(type default)
			)
			(layer "F.SilkS")
		)
		(fp_line
			(start -1.299972 -7.138924)
			(end -1.299972 -4.71678)
			(stroke
				(width 0.1524)
				(type default)
			)
			(layer "F.SilkS")
		)
		(fp_line
			(start -1.299972 -9.838944)
			(end -2.899918 -9.838944)
			(stroke
				(width 0.1524)
				(type default)
			)
			(layer "F.SilkS")
		)
		(fp_line
			(start -1.299972 -11.494008)
			(end -1.299972 -9.838944)
			(stroke
				(width 0.1524)
				(type default)
			)
			(layer "F.SilkS")
		)
		(fp_line
			(start -2.899918 17.85112)
			(end -1.299972 17.85112)
			(stroke
				(width 0.1524)
				(type default)
			)
			(layer "F.SilkS")
		)
		(fp_line
			(start -2.899918 15.1511)
			(end -2.899918 17.85112)
			(stroke
				(width 0.1524)
				(type default)
			)
			(layer "F.SilkS")
		)
		(fp_line
			(start -2.899918 -7.138924)
			(end -1.299972 -7.138924)
			(stroke
				(width 0.1524)
				(type default)
			)
			(layer "F.SilkS")
		)
		(fp_line
			(start -2.899918 -9.838944)
			(end -2.899918 -7.138924)
			(stroke
				(width 0.1524)
				(type default)
			)
			(layer "F.SilkS")
		)
		(fp_poly
			(pts
				(xy -3.096006 0.764286) (xy -3.096006 -0.759714) (xy -1.572006 0.002286)
			)
			(stroke
				(width 0)
				(type default)
			)
			(fill yes)
			(layer "F.SilkS")
		)
		(fp_poly
			(pts
				(xy 2.122424 -2.148332) (xy 2.122424 9.778238) (xy -0.6223 9.778238) (xy -0.6223 -2.148332)
			)
			(stroke
				(width 0)
				(type default)
			)
			(fill no)
			(layer "B.CrtYd")
		)
		(fp_poly
			(pts
				(arc
					(start 0.299974 14.73581)
					(mid -0.095157 14.899479)
					(end -0.258826 15.29461)
				)
				(arc
					(start -0.258826 17.70761)
					(mid -0.095157 18.102741)
					(end 0.299974 18.26641)
				)
				(arc
					(start 0.299974 18.26641)
					(mid 0.695105 18.102741)
					(end 0.858774 17.70761)
				)
				(arc
					(start 0.858774 15.29461)
					(mid 0.695105 14.899479)
					(end 0.299974 14.73581)
				)
			)
			(stroke
				(width 0)
				(type default)
			)
			(fill no)
			(layer "B.CrtYd")
		)
		(fp_poly
			(pts
				(arc
					(start 0.299974 -10.254234)
					(mid -0.095157 -10.090565)
					(end -0.258826 -9.695434)
				)
				(arc
					(start -0.258826 -7.282434)
					(mid -0.095157 -6.887303)
					(end 0.299974 -6.723634)
				)
				(arc
					(start 0.299974 -6.723634)
					(mid 0.695105 -6.887303)
					(end 0.858774 -7.282434)
				)
				(arc
					(start 0.858774 -9.695434)
					(mid 0.695105 -10.090565)
					(end 0.299974 -10.254234)
				)
			)
			(stroke
				(width 0)
				(type default)
			)
			(fill no)
			(layer "B.CrtYd")
		)
		(fp_poly
			(pts
				(arc
					(start 0.503428 11.995912)
					(mid -1.50368 11.995912)
					(end 0.503428 11.995912)
				)
			)
			(stroke
				(width 0)
				(type default)
			)
			(fill no)
			(layer "B.CrtYd")
		)
		(fp_poly
			(pts
				(arc
					(start 0.503428 -3.98399)
					(mid -1.50368 -3.98399)
					(end 0.503428 -3.98399)
				)
			)
			(stroke
				(width 0)
				(type default)
			)
			(fill no)
			(layer "B.CrtYd")
		)
		(fp_poly
			(pts
				(xy -2.899918 -9.838944) (xy -1.299972 -9.838944) (xy -1.299972 -11.494008) (xy 9.299956 -11.494008)
				(xy 9.299956 19.50593) (xy -1.299972 19.50593) (xy -1.299972 17.85112) (xy -2.899918 17.85112) (xy -2.899918 15.1511)
				(xy -1.299972 15.1511) (xy -1.299972 12.999212) (xy -1.503172 12.999212) (xy -1.503172 10.992612)
				(xy -1.299972 10.992612) (xy -1.299972 -2.98069) (xy -1.503172 -2.98069) (xy -1.503172 -4.98729)
				(xy -1.299972 -4.98729) (xy -1.299972 -7.138924) (xy -2.899918 -7.138924)
			)
			(stroke
				(width 0)
				(type default)
			)
			(fill no)
			(layer "F.CrtYd")
		)
		(fp_line
			(start 9.299956 19.50593)
			(end 9.299956 -11.494008)
			(stroke
				(width 0.1)
				(type default)
			)
			(layer "F.Fab")
		)
		(fp_line
			(start 9.299956 -11.494008)
			(end -1.299972 -11.494008)
			(stroke
				(width 0.1)
				(type default)
			)
			(layer "F.Fab")
		)
		(fp_line
			(start -1.299972 19.50593)
			(end 9.299956 19.50593)
			(stroke
				(width 0.1)
				(type default)
			)
			(layer "F.Fab")
		)
		(fp_line
			(start -1.299972 17.85112)
			(end -1.299972 19.50593)
			(stroke
				(width 0.1)
				(type default)
			)
			(layer "F.Fab")
		)
		(fp_line
			(start -1.299972 15.1511)
			(end -2.899918 15.1511)
			(stroke
				(width 0.1)
				(type default)
			)
			(layer "F.Fab")
		)
		(fp_line
			(start -1.299972 -7.138924)
			(end -1.299972 15.1511)
			(stroke
				(width 0.1)
				(type default)
			)
			(layer "F.Fab")
		)
		(fp_line
			(start -1.299972 -9.838944)
			(end -2.899918 -9.838944)
			(stroke
				(width 0.1)
				(type default)
			)
			(layer "F.Fab")
		)
		(fp_line
			(start -1.299972 -11.494008)
			(end -1.299972 -9.838944)
			(stroke
				(width 0.1)
				(type default)
			)
			(layer "F.Fab")
		)
		(fp_line
			(start -2.899918 17.85112)
			(end -1.299972 17.85112)
			(stroke
				(width 0.1)
				(type default)
			)
			(layer "F.Fab")
		)
		(fp_line
			(start -2.899918 15.1511)
			(end -2.899918 17.85112)
			(stroke
				(width 0.1)
				(type default)
			)
			(layer "F.Fab")
		)
		(fp_line
			(start -2.899918 -7.138924)
			(end -1.299972 -7.138924)
			(stroke
				(width 0.1)
				(type default)
			)
			(layer "F.Fab")
		)
		(fp_line
			(start -2.899918 -9.838944)
			(end -2.899918 -7.138924)
			(stroke
				(width 0.1)
				(type default)
			)
			(layer "F.Fab")
		)
		(fp_poly
			(pts
				(xy -3.096006 0.764286) (xy -3.096006 -0.759714) (xy -1.572006 0.002286)
			)
			(stroke
				(width 0)
				(type default)
			)
			(fill yes)
			(layer "F.Fab")
		)
		(fp_text user "11"
			(at 1.537462 -12.184126 0)
			(unlocked yes)
			(layer "F.SilkS")
			(effects
				(font
					(size 0.7874 0.5842)
					(thickness 0.1524)
				)
			)
		)
		(fp_text user "15"
			(at -0.766318 20.236942 0)
			(unlocked yes)
			(layer "F.SilkS")
			(effects
				(font
					(size 0.7874 0.5842)
					(thickness 0.1524)
				)
			)
		)
		(fp_text user "6"
			(at -1.76149 -1.074928 0)
			(unlocked yes)
			(layer "F.SilkS")
			(effects
				(font
					(size 0.7874 0.5842)
					(thickness 0.1524)
				)
			)
		)
		(fp_text user "5"
			(at -1.881378 10.684256 0)
			(unlocked yes)
			(layer "F.SilkS")
			(effects
				(font
					(size 0.7874 0.5842)
					(thickness 0.1524)
				)
			)
		)
		(fp_text user "11"
			(at 1.624838 -2.163318 0)
			(unlocked yes)
			(layer "B.SilkS")
			(effects
				(font
					(size 0.7874 0.5842)
					(thickness 0.1524)
				)
				(justify mirror)
			)
		)
		(fp_text user "15"
			(at 1.609598 9.572752 0)
			(unlocked yes)
			(layer "B.SilkS")
			(effects
				(font
					(size 0.7874 0.5842)
					(thickness 0.1524)
				)
				(justify mirror)
			)
		)
		(fp_text user "5"
			(at -1.04394 8.918702 0)
			(unlocked yes)
			(layer "B.SilkS")
			(effects
				(font
					(size 0.7874 0.5842)
					(thickness 0.1524)
				)
				(justify mirror)
			)
		)
		(fp_text user "6"
			(at -1.32588 -1.558544 0)
			(unlocked yes)
			(layer "B.SilkS")
			(effects
				(font
					(size 0.7874 0.5842)
					(thickness 0.1524)
				)
				(justify mirror)
			)
		)
		(fp_text user "15"
			(at 1.503426 9.986772 90)
			(unlocked yes)
			(layer "B.Fab")
			(effects
				(font
					(size 0.7874 0.5842)
					(thickness 0.000001)
				)
				(justify mirror)
			)
		)
		(fp_text user "11"
			(at 1.457452 -2.364486 90)
			(unlocked yes)
			(layer "B.Fab")
			(effects
				(font
					(size 0.7874 0.5842)
					(thickness 0.000001)
				)
				(justify mirror)
			)
		)
		(fp_text user "6"
			(at 0.021336 -2.64033 90)
			(unlocked yes)
			(layer "B.Fab")
			(effects
				(font
					(size 0.7874 0.5842)
					(thickness 0.000001)
				)
				(justify mirror)
			)
		)
		(fp_text user "5"
			(at -0.036068 10.411714 90)
			(unlocked yes)
			(layer "B.Fab")
			(effects
				(font
					(size 0.7874 0.5842)
					(thickness 0.000001)
				)
				(justify mirror)
			)
		)
		(fp_text user "15"
			(at 1.641348 20.534122 90)
			(unlocked yes)
			(layer "F.Fab")
			(effects
				(font
					(size 0.7874 0.5842)
					(thickness 0.000001)
				)
			)
		)
		(fp_text user "11"
			(at 1.53797 -12.45235 90)
			(unlocked yes)
			(layer "F.Fab")
			(effects
				(font
					(size 0.7874 0.5842)
					(thickness 0.000001)
				)
			)
		)
		(fp_text user "5"
			(at 0.124714 20.350226 90)
			(unlocked yes)
			(layer "F.Fab")
			(effects
				(font
					(size 0.7874 0.5842)
					(thickness 0.000001)
				)
			)
		)
		(fp_text user "6"
			(at 0.044196 -12.291568 90)
			(unlocked yes)
			(layer "F.Fab")
			(effects
				(font
					(size 0.7874 0.5842)
					(thickness 0.000001)
				)
			)
		)
		(pad "" np_thru_hole circle
			(at -0.499872 -3.98399 90)
			(size 1.4986 1.4986)
			(drill 1.4986)
			(layers "*.Cu" "*.Mask")
			(clearance 0.381)
			(thermal_gap 0.381)
		)
		(pad "" np_thru_hole circle
			(at -0.499872 11.995912 90)
			(size 1.4986 1.4986)
			(drill 1.4986)
			(layers "*.Cu" "*.Mask")
			(clearance 0.381)
			(thermal_gap 0.381)
		)
		(pad "1" thru_hole rect
			(at 0 0 90)
			(size 1.143 1.143)
			(drill 0.8382)
			(layers "*.Cu" "*.Mask")
			(remove_unused_layers no)
			(net "CRT_R")
			(clearance 0.1016)
			(thermal_gap 0.1016)
			(padstack
				(mode front_inner_back)
				(layer "Inner"
					(shape circle)
					(size 1.143 1.143)
					(clearance 0.1016)
				)
				(layer "B.Cu"
					(shape rect)
					(size 1.143 1.143)
					(clearance 0.1016)
				)
			)
		)
		(pad "2" thru_hole circle
			(at 1.500124 2.289048 90)
			(size 1.143 1.143)
			(drill 0.8382)
			(layers "*.Cu" "*.Mask")
			(remove_unused_layers no)
			(net "CRT_G")
			(clearance 0.1016)
			(thermal_gap 0.1016)
		)
		(pad "3" thru_hole circle
			(at 0 4.578096 90)
			(size 1.143 1.143)
			(drill 0.8382)
			(layers "*.Cu" "*.Mask")
			(remove_unused_layers no)
			(net "CRT_B")
			(clearance 0.1016)
			(thermal_gap 0.1016)
		)
		(pad "4" thru_hole circle
			(at 1.500124 6.86689 90)
			(size 1.143 1.143)
			(drill 0.8382)
			(layers "*.Cu" "*.Mask")
			(remove_unused_layers no)
			(net "Net_2246")
			(clearance 0.1016)
			(thermal_gap 0.1016)
		)
		(pad "5" thru_hole circle
			(at 0 9.155938 90)
			(size 1.143 1.143)
			(drill 0.8382)
			(layers "*.Cu" "*.Mask")
			(remove_unused_layers no)
			(net "GND")
			(clearance 0.1016)
			(thermal_gap 0.1016)
		)
		(pad "6" thru_hole circle
			(at 0 -1.526032 90)
			(size 1.143 1.143)
			(drill 0.8382)
			(layers "*.Cu" "*.Mask")
			(remove_unused_layers no)
			(net "GND")
			(clearance 0.1016)
			(thermal_gap 0.1016)
		)
		(pad "7" thru_hole circle
			(at 1.500124 0.763016 90)
			(size 1.143 1.143)
			(drill 0.8382)
			(layers "*.Cu" "*.Mask")
			(remove_unused_layers no)
			(net "GND")
			(clearance 0.1016)
			(thermal_gap 0.1016)
		)
		(pad "8" thru_hole circle
			(at 0 3.052064 90)
			(size 1.143 1.143)
			(drill 0.8382)
			(layers "*.Cu" "*.Mask")
			(remove_unused_layers no)
			(net "GND")
			(clearance 0.1016)
			(thermal_gap 0.1016)
		)
		(pad "9" thru_hole circle
			(at 1.500124 5.341112 90)
			(size 1.143 1.143)
			(drill 0.8382)
			(layers "*.Cu" "*.Mask")
			(remove_unused_layers no)
			(net "P5V_CRT")
			(clearance 0.1016)
			(thermal_gap 0.1016)
		)
		(pad "10" thru_hole circle
			(at 0 7.629906 90)
			(size 1.143 1.143)
			(drill 0.8382)
			(layers "*.Cu" "*.Mask")
			(remove_unused_layers no)
			(net "GND")
			(clearance 0.1016)
			(thermal_gap 0.1016)
		)
		(pad "11" thru_hole circle
			(at 1.500124 -0.763016 90)
			(size 1.143 1.143)
			(drill 0.8382)
			(layers "*.Cu" "*.Mask")
			(remove_unused_layers no)
			(net "Net_2247")
			(clearance 0.1016)
			(thermal_gap 0.1016)
		)
		(pad "12" thru_hole circle
			(at 0 1.526032 90)
			(size 1.143 1.143)
			(drill 0.8382)
			(layers "*.Cu" "*.Mask")
			(remove_unused_layers no)
			(net "CRT_DDCDATA")
			(clearance 0.1016)
			(thermal_gap 0.1016)
		)
		(pad "13" thru_hole circle
			(at 1.500124 3.81508 90)
			(size 1.143 1.143)
			(drill 0.8382)
			(layers "*.Cu" "*.Mask")
			(remove_unused_layers no)
			(net "CRT_HSYNC")
			(clearance 0.1016)
			(thermal_gap 0.1016)
		)
		(pad "14" thru_hole circle
			(at 0 6.103874 90)
			(size 1.143 1.143)
			(drill 0.8382)
			(layers "*.Cu" "*.Mask")
			(remove_unused_layers no)
			(net "CRT_VSYNC")
			(clearance 0.1016)
			(thermal_gap 0.1016)
		)
		(pad "15" thru_hole circle
			(at 1.500124 8.392922 90)
			(size 1.143 1.143)
			(drill 0.8382)
			(layers "*.Cu" "*.Mask")
			(remove_unused_layers no)
			(net "CRT_DDCCLK")
			(clearance 0.1016)
			(thermal_gap 0.1016)
		)
		(pad "G1" thru_hole oval
			(at 0.299974 -8.488934 180)
			(size 1.016 3.429)
			(drill oval 0.7112 3.1496)
			(layers "*.Cu" "*.Mask")
			(remove_unused_layers no)
			(net "GND")
			(clearance 0.2286)
			(thermal_gap 0.2286)
		)
		(pad "G2" thru_hole oval
			(at 0.299974 16.50111 180)
			(size 1.016 3.429)
			(drill oval 0.7112 3.1496)
			(layers "*.Cu" "*.Mask")
			(remove_unused_layers no)
			(net "GND")
			(clearance 0.2286)
			(thermal_gap 0.2286)
		)
		(zone
			(layers "F.Cu" "B.Cu" "In1.Cu" "In2.Cu" "In3.Cu" "In4.Cu" "In5.Cu" "In6.Cu"
				"In7.Cu" "In8.Cu"
			)
			(hatch none 0.5)
			(connect_pads
				(clearance 0)
			)
			(min_thickness 0.25)
			(keepout
				(tracks not_allowed)
				(vias allowed)
				(pads allowed)
				(copperpour not_allowed)
				(footprints allowed)
			)
			(placement
				(enabled no)
				(sheetname "")
			)
			(fill
				(thermal_gap 0.5)
				(thermal_bridge_width 0.5)
				(island_removal_mode 0)
			)
			(polygon
				(pts
					(arc
						(start 9.994392 -58.790078)
						(mid 12.3063 -58.790078)
						(end 9.994392 -58.790078)
					)
				)
			)
		)
		(zone
			(layers "F.Cu" "B.Cu" "In1.Cu" "In2.Cu" "In3.Cu" "In4.Cu" "In5.Cu" "In6.Cu"
				"In7.Cu" "In8.Cu"
			)
			(hatch none 0.5)
			(connect_pads
				(clearance 0)
			)
			(min_thickness 0.25)
			(keepout
				(tracks not_allowed)
				(vias allowed)
				(pads allowed)
				(copperpour not_allowed)
				(footprints allowed)
			)
			(placement
				(enabled no)
				(sheetname "")
			)
			(fill
				(thermal_gap 0.5)
				(thermal_bridge_width 0.5)
				(island_removal_mode 0)
			)
			(polygon
				(pts
					(arc
						(start 9.994392 -42.810176)
						(mid 12.3063 -42.810176)
						(end 9.994392 -42.810176)
					)
				)
			)
		)
	)
	(footprint ""
		(layer "F.Cu")
		(at 177.649632 -144.87652)
		(property "Reference" "C446"
			(at -5.210302 0.071628 0)
			(unlocked yes)
			(layer "F.SilkS")
			(effects
				(font
					(size 0.7874 0.5842)
					(thickness 0.1524)
				)
				(justify left)
			)
		)
		(property "Value" ""
			(at 0 0 0)
			(layer "F.Fab")
			(effects
				(font
					(size 1.27 1.27)
				)
			)
		)
		(duplicate_pad_numbers_are_jumpers no)
		(fp_line
			(start -1.905 -0.8636)
			(end 1.905 -0.8636)
			(stroke
				(width 0.1524)
				(type default)
			)
			(layer "F.SilkS")
		)
		(fp_line
			(start -1.905 0.8636)
			(end -1.905 -0.8636)
			(stroke
				(width 0.1524)
				(type default)
			)
			(layer "F.SilkS")
		)
		(fp_line
			(start 0 0.8382)
			(end 0 -0.8382)
			(stroke
				(width 0.1524)
				(type default)
			)
			(layer "F.SilkS")
		)
		(fp_line
			(start 1.905 -0.8636)
			(end 1.905 0.8636)
			(stroke
				(width 0.1524)
				(type default)
			)
			(layer "F.SilkS")
		)
		(fp_line
			(start 1.905 0.8636)
			(end -1.905 0.8636)
			(stroke
				(width 0.1524)
				(type default)
			)
			(layer "F.SilkS")
		)
		(fp_rect
			(start -1.524 0.7366)
			(end 1.524 -0.7366)
			(stroke
				(width 0)
				(type default)
			)
			(fill no)
			(layer "F.CrtYd")
		)
		(pad "1" smd rect
			(at 0.94996 0)
			(size 1.1176 1.3716)
			(layers "F.Cu" "F.Mask" "F.Paste")
			(net "P3V3_NODE1")
		)
		(pad "2" smd rect
			(at -0.94996 0)
			(size 1.1176 1.3716)
			(layers "F.Cu" "F.Mask" "F.Paste")
			(net "GND")
		)
	)
)
